(kicad_pcb
	(version 20241229)
	(generator "pcbnew")
	(generator_version "9.0")
	(general
		(thickness 1.62)
		(legacy_teardrops no)
	)
	(paper "A4")
	(title_block
		(title "OCuLink to 10GbE adapter")
		(date "2026-02-23")
		(rev "1.1.0")
		(company "Antmicro Ltd")
		(comment 1 "www.antmicro.com")
		(comment 9 "footprints 203-208 of 510")
	)
	(layers
		(0 "F.Cu" signal)
		(4 "In1.Cu" signal)
		(6 "In2.Cu" signal)
		(8 "In3.Cu" signal)
		(10 "In4.Cu" signal)
		(12 "In5.Cu" signal)
		(14 "In6.Cu" signal)
		(2 "B.Cu" signal)
		(9 "F.Adhes" user "F.Adhesive")
		(11 "B.Adhes" user "B.Adhesive")
		(13 "F.Paste" user)
		(15 "B.Paste" user)
		(5 "F.SilkS" user "F.Silkscreen")
		(7 "B.SilkS" user "B.Silkscreen")
		(1 "F.Mask" user)
		(3 "B.Mask" user)
		(17 "Dwgs.User" user "User.Drawings")
		(19 "Cmts.User" user "User.Comments")
		(21 "Eco1.User" user "User.Eco1")
		(23 "Eco2.User" user "User.Eco2")
		(25 "Edge.Cuts" user)
		(27 "Margin" user)
		(31 "F.CrtYd" user "F.Courtyard")
		(29 "B.CrtYd" user "B.Courtyard")
		(35 "F.Fab" user)
		(33 "B.Fab" user)
	)
	(footprint "antmicro-footprints:R_0402_1005Metric"
		(layer "F.Cu")
		(at 83.85 57.771999)
		(descr "Resistor SMD 0402")
		(tags "resistor SMD 0402")
		(property "Reference" "R23"
			(at -0.67 1.330001 0)
			(layer "F.SilkS")
			(effects
				(font
					(size 0.7 0.7)
					(thickness 0.15)
				)
				(justify left bottom)
			)
		)
		(property "Value" "R_5k1_0402"
			(at -1.011843 1.772046 0)
			(layer "F.Fab")
			(hide yes)
			(effects
				(font
					(size 0.7 0.7)
					(thickness 0.15)
				)
				(justify left bottom)
			)
		)
		(property "Datasheet" "https://www.bourns.com/docs/product-datasheets/cr.pdf"
			(at 0 0 0)
			(layer "F.Fab")
			(hide yes)
			(effects
				(font
					(size 1.27 1.27)
					(thickness 0.15)
				)
			)
		)
		(property "Description" "SMD Chip Resistor, 5.1 kohm, ± 1%, 63 mW, 0402 [1005 Metric], Thick Film, General Purpose"
			(at 0 0 0)
			(layer "F.Fab")
			(hide yes)
			(effects
				(font
					(size 1.27 1.27)
					(thickness 0.15)
				)
			)
		)
		(property "MPN" "CR0402-FX-5101GLF"
			(at 0 0 0)
			(unlocked yes)
			(layer "F.Fab")
			(hide yes)
			(effects
				(font
					(size 1 1)
					(thickness 0.15)
				)
			)
		)
		(property "Manufacturer" "Bourns"
			(at 0 0 0)
			(unlocked yes)
			(layer "F.Fab")
			(hide yes)
			(effects
				(font
					(size 1 1)
					(thickness 0.15)
				)
			)
		)
		(property "License" "Apache-2.0"
			(at 0 0 0)
			(unlocked yes)
			(layer "F.Fab")
			(hide yes)
			(effects
				(font
					(size 1 1)
					(thickness 0.15)
				)
			)
		)
		(property "Author" "Antmicro"
			(at 0 0 0)
			(unlocked yes)
			(layer "F.Fab")
			(hide yes)
			(effects
				(font
					(size 1 1)
					(thickness 0.15)
				)
			)
		)
		(property "Val" "5k1"
			(at 0 0 0)
			(unlocked yes)
			(layer "F.Fab")
			(hide yes)
			(effects
				(font
					(size 1 1)
					(thickness 0.15)
				)
			)
		)
		(property "Tolerance" "1%"
			(at 0 0 0)
			(unlocked yes)
			(layer "F.Fab")
			(hide yes)
			(effects
				(font
					(size 1 1)
					(thickness 0.15)
				)
			)
		)
		(sheetname "/Power/")
		(sheetfile "power.kicad_sch")
		(attr smd)
		(fp_rect
			(start -0.925 -0.47)
			(end 0.925 0.47)
			(stroke
				(width 0.05)
				(type default)
			)
			(fill no)
			(layer "F.CrtYd")
		)
		(fp_rect
			(start -0.5 -0.25)
			(end 0.5 0.25)
			(stroke
				(width 0.15)
				(type solid)
			)
			(fill no)
			(layer "F.Fab")
		)
		(pad "1" smd roundrect
			(at -0.48 0)
			(size 0.59 0.64)
			(layers "F.Cu" "F.Mask" "F.Paste")
			(roundrect_rratio 0.25)
			(net 28 "GND")
			(pintype "passive")
		)
		(pad "2" smd roundrect
			(at 0.48 0)
			(size 0.59 0.64)
			(layers "F.Cu" "F.Mask" "F.Paste")
			(roundrect_rratio 0.25)
			(net 357 "/Power/CC1")
			(pintype "passive")
		)
	)
	(footprint "antmicro-footprints:C_0402_1005Metric"
		(layer "F.Cu")
		(at 97.399999 108.1)
		(descr "Capacitor SMD 0402")
		(tags "capacitor SMD 0402")
		(property "Reference" "C68"
			(at -2.249999 15.625 0)
			(layer "F.SilkS")
			(effects
				(font
					(size 0.7 0.7)
					(thickness 0.15)
				)
				(justify left bottom)
			)
		)
		(property "Value" "C_100n_0402"
			(at -1.022927 2.155213 0)
			(layer "F.Fab")
			(hide yes)
			(effects
				(font
					(size 0.7 0.7)
					(thickness 0.15)
				)
				(justify left bottom)
			)
		)
		(property "Datasheet" "https://www.murata.com/products/productdetail?partno=GRM155R61H104KE14%23"
			(at 0 0 0)
			(layer "F.Fab")
			(hide yes)
			(effects
				(font
					(size 1.27 1.27)
					(thickness 0.15)
				)
			)
		)
		(property "Description" "SMD Multilayer Ceramic Capacitor, 0.1 µF, 50 V, 0402 [1005 Metric], ± 10%, X5R, GRM Series"
			(at 0 0 0)
			(layer "F.Fab")
			(hide yes)
			(effects
				(font
					(size 1.27 1.27)
					(thickness 0.15)
				)
			)
		)
		(property "MPN" "GRM155R61H104KE14D"
			(at 0 0 0)
			(unlocked yes)
			(layer "F.Fab")
			(hide yes)
			(effects
				(font
					(size 1 1)
					(thickness 0.15)
				)
			)
		)
		(property "Val" "100n"
			(at 0 0 0)
			(unlocked yes)
			(layer "F.Fab")
			(hide yes)
			(effects
				(font
					(size 1 1)
					(thickness 0.15)
				)
			)
		)
		(property "Voltage" "50V"
			(at 0 0 0)
			(unlocked yes)
			(layer "F.Fab")
			(hide yes)
			(effects
				(font
					(size 1 1)
					(thickness 0.15)
				)
			)
		)
		(property "Dielectric" "X5R"
			(at 0 0 0)
			(unlocked yes)
			(layer "F.Fab")
			(hide yes)
			(effects
				(font
					(size 1 1)
					(thickness 0.15)
				)
			)
		)
		(property "Manufacturer" "Murata"
			(at 0 0 0)
			(unlocked yes)
			(layer "F.Fab")
			(hide yes)
			(effects
				(font
					(size 1 1)
					(thickness 0.15)
				)
			)
		)
		(property "License" "Apache-2.0"
			(at 0 0 0)
			(unlocked yes)
			(layer "F.Fab")
			(hide yes)
			(effects
				(font
					(size 1 1)
					(thickness 0.15)
				)
			)
		)
		(property "Author" "Antmicro"
			(at 0 0 0)
			(unlocked yes)
			(layer "F.Fab")
			(hide yes)
			(effects
				(font
					(size 1 1)
					(thickness 0.15)
				)
			)
		)
		(sheetname "/X710-AT2 10GbE/")
		(sheetfile "x710-at2-10gbe.kicad_sch")
		(attr smd)
		(fp_rect
			(start -0.925 -0.47)
			(end 0.925 0.47)
			(stroke
				(width 0.05)
				(type default)
			)
			(fill no)
			(layer "F.CrtYd")
		)
		(fp_line
			(start -0.494 -0.25)
			(end 0.504 -0.25)
			(stroke
				(width 0.15)
				(type solid)
			)
			(layer "F.Fab")
		)
		(fp_line
			(start -0.494 0.248)
			(end -0.494 -0.25)
			(stroke
				(width 0.15)
				(type solid)
			)
			(layer "F.Fab")
		)
		(fp_line
			(start 0.504 -0.25)
			(end 0.504 0.248)
			(stroke
				(width 0.15)
				(type solid)
			)
			(layer "F.Fab")
		)
		(fp_line
			(start 0.504 0.248)
			(end -0.494 0.248)
			(stroke
				(width 0.15)
				(type solid)
			)
			(layer "F.Fab")
		)
		(pad "1" smd roundrect
			(at -0.48 0)
			(size 0.59 0.64)
			(layers "F.Cu" "F.Mask" "F.Paste")
			(roundrect_rratio 0.25)
			(net 29 "/X710-AT2 10GbE/25MHZ_OSC.+")
			(pintype "passive")
		)
		(pad "2" smd roundrect
			(at 0.48 0)
			(size 0.59 0.64)
			(layers "F.Cu" "F.Mask" "F.Paste")
			(roundrect_rratio 0.25)
			(net 30 "/X710-AT2 10GbE/25MHZ_OSC_AC.+")
			(pintype "passive")
		)
	)
	(footprint "antmicro-footprints:R_0603_1608Metric"
		(layer "F.Cu")
		(at 63.199998 91.8)
		(descr "Resistor SMD 0603")
		(tags "resistor SMD 0603")
		(property "Reference" "R28"
			(at -0.41795 -0.496932 0)
			(layer "F.SilkS")
			(effects
				(font
					(size 0.7 0.7)
					(thickness 0.15)
				)
				(justify left bottom)
			)
		)
		(property "Value" "R_0R_22.4A_0603"
			(at 0 1.6 0)
			(layer "F.Fab")
			(hide yes)
			(effects
				(font
					(size 0.7 0.7)
					(thickness 0.15)
				)
				(justify left bottom)
			)
		)
		(property "Datasheet" "https://fscdn.rohm.com/en/products/databook/datasheet/passive/resistor/chip_resistor/pmr-jpw-e.pdf"
			(at 0 0 0)
			(layer "F.Fab")
			(hide yes)
			(effects
				(font
					(size 1.27 1.27)
					(thickness 0.15)
				)
			)
		)
		(property "Description" "SMD Chip Resistor"
			(at 0 0 0)
			(layer "F.Fab")
			(hide yes)
			(effects
				(font
					(size 1.27 1.27)
					(thickness 0.15)
				)
			)
		)
		(property "MPN" "PMR03EZPJ000"
			(at 0 0 0)
			(unlocked yes)
			(layer "F.Fab")
			(hide yes)
			(effects
				(font
					(size 1 1)
					(thickness 0.15)
				)
			)
		)
		(property "Manufacturer" "ROHM Semiconductor"
			(at 0 0 0)
			(unlocked yes)
			(layer "F.Fab")
			(hide yes)
			(effects
				(font
					(size 1 1)
					(thickness 0.15)
				)
			)
		)
		(property "Val" "0R"
			(at 0 0 0)
			(unlocked yes)
			(layer "F.Fab")
			(hide yes)
			(effects
				(font
					(size 1 1)
					(thickness 0.15)
				)
			)
		)
		(property "Max. Curr." "22.4A"
			(at 0 0 0)
			(unlocked yes)
			(layer "F.Fab")
			(hide yes)
			(effects
				(font
					(size 1 1)
					(thickness 0.15)
				)
			)
		)
		(property "Author" "Antmicro"
			(at 0 0 0)
			(unlocked yes)
			(layer "F.Fab")
			(hide yes)
			(effects
				(font
					(size 1 1)
					(thickness 0.15)
				)
			)
		)
		(property "License" "Apache-2.0"
			(at 0 0 0)
			(unlocked yes)
			(layer "F.Fab")
			(hide yes)
			(effects
				(font
					(size 1 1)
					(thickness 0.15)
				)
			)
		)
		(property "Tolerance" "template_tolerance"
			(at 0 0 0)
			(unlocked yes)
			(layer "F.Fab")
			(hide yes)
			(effects
				(font
					(size 1 1)
					(thickness 0.15)
				)
			)
		)
		(sheetname "/Power/")
		(sheetfile "power.kicad_sch")
		(attr smd)
		(fp_line
			(start -0.15 -0.4)
			(end 0.15 -0.4)
			(stroke
				(width 0.15)
				(type solid)
			)
			(layer "F.SilkS")
		)
		(fp_line
			(start -0.15 0.4)
			(end 0.15 0.4)
			(stroke
				(width 0.15)
				(type solid)
			)
			(layer "F.SilkS")
		)
		(fp_rect
			(start -1.25 -0.65)
			(end 1.25 0.65)
			(stroke
				(width 0.05)
				(type solid)
			)
			(fill no)
			(layer "F.CrtYd")
		)
		(fp_rect
			(start -0.8 -0.4)
			(end 0.8 0.4)
			(stroke
				(width 0.15)
				(type solid)
			)
			(fill no)
			(layer "F.Fab")
		)
		(pad "1" smd roundrect
			(at -0.7 0)
			(size 0.8 1)
			(layers "F.Cu" "F.Mask" "F.Paste")
			(roundrect_rratio 0.2)
			(net 311 "/Power/+DVDD_OUT")
			(pintype "passive")
		)
		(pad "2" smd roundrect
			(at 0.7 0)
			(size 0.8 1)
			(layers "F.Cu" "F.Mask" "F.Paste")
			(roundrect_rratio 0.2)
			(net 6 "DVDD")
			(pintype "passive")
		)
	)
	(footprint "antmicro-footprints:R_0402_1005Metric"
		(layer "F.Cu")
		(at 107.6 112.5 180)
		(descr "Resistor SMD 0402")
		(tags "resistor SMD 0402")
		(property "Reference" "R43"
			(at -3.21 -0.63 0)
			(layer "F.SilkS")
			(effects
				(font
					(size 0.7 0.7)
					(thickness 0.15)
				)
				(justify right top)
			)
		)
		(property "Value" "R_10k_0402"
			(at -1.011843 1.772046 0)
			(layer "F.Fab")
			(hide yes)
			(effects
				(font
					(size 0.7 0.7)
					(thickness 0.15)
				)
				(justify right top)
			)
		)
		(property "Datasheet" "https://www.bourns.com/docs/product-datasheets/cr.pdf"
			(at 0 0 0)
			(layer "F.Fab")
			(hide yes)
			(effects
				(font
					(size 1.27 1.27)
					(thickness 0.15)
				)
			)
		)
		(property "Description" "SMD Chip Resistor, 10 kohm, ± 1%, 62.5 mW, 0402 [1005 Metric], Thick Film, General Purpose"
			(at 0 0 0)
			(layer "F.Fab")
			(hide yes)
			(effects
				(font
					(size 1.27 1.27)
					(thickness 0.15)
				)
			)
		)
		(property "MPN" "CR0402-FX-1002GLF"
			(at 0 0 180)
			(unlocked yes)
			(layer "F.Fab")
			(hide yes)
			(effects
				(font
					(size 1 1)
					(thickness 0.15)
				)
			)
		)
		(property "Manufacturer" "Bourns"
			(at 0 0 180)
			(unlocked yes)
			(layer "F.Fab")
			(hide yes)
			(effects
				(font
					(size 1 1)
					(thickness 0.15)
				)
			)
		)
		(property "License" "Apache-2.0"
			(at 0 0 180)
			(unlocked yes)
			(layer "F.Fab")
			(hide yes)
			(effects
				(font
					(size 1 1)
					(thickness 0.15)
				)
			)
		)
		(property "Author" "Antmicro"
			(at 0 0 180)
			(unlocked yes)
			(layer "F.Fab")
			(hide yes)
			(effects
				(font
					(size 1 1)
					(thickness 0.15)
				)
			)
		)
		(property "Val" "10k"
			(at 0 0 180)
			(unlocked yes)
			(layer "F.Fab")
			(hide yes)
			(effects
				(font
					(size 1 1)
					(thickness 0.15)
				)
			)
		)
		(property "Tolerance" "1%"
			(at 0 0 180)
			(unlocked yes)
			(layer "F.Fab")
			(hide yes)
			(effects
				(font
					(size 1 1)
					(thickness 0.15)
				)
			)
		)
		(sheetname "/X710-AT2 10GbE/")
		(sheetfile "x710-at2-10gbe.kicad_sch")
		(attr smd)
		(fp_rect
			(start -0.925 -0.47)
			(end 0.925 0.47)
			(stroke
				(width 0.05)
				(type default)
			)
			(fill no)
			(layer "F.CrtYd")
		)
		(fp_rect
			(start -0.5 -0.25)
			(end 0.5 0.25)
			(stroke
				(width 0.15)
				(type solid)
			)
			(fill no)
			(layer "F.Fab")
		)
		(pad "1" smd roundrect
			(at -0.48 0 180)
			(size 0.59 0.64)
			(layers "F.Cu" "F.Mask" "F.Paste")
			(roundrect_rratio 0.25)
			(net 74 "/X710-AT2 10GbE/3V3_OSC")
			(pintype "passive")
		)
		(pad "2" smd roundrect
			(at 0.48 0 180)
			(size 0.59 0.64)
			(layers "F.Cu" "F.Mask" "F.Paste")
			(roundrect_rratio 0.25)
			(net 149 "/X710-AT2 10GbE/EN_OSC")
			(pintype "passive")
		)
	)
	(footprint "antmicro-footprints:R_0402_1005Metric"
		(layer "F.Cu")
		(at 99.16 90.1645 180)
		(descr "Resistor SMD 0402")
		(tags "resistor SMD 0402")
		(property "Reference" "R95"
			(at -1.04 -0.5355 0)
			(layer "F.SilkS")
			(effects
				(font
					(size 0.7 0.7)
					(thickness 0.15)
				)
				(justify right top)
			)
		)
		(property "Value" "R_0R_0402"
			(at -1.011843 1.772047 0)
			(layer "F.Fab")
			(hide yes)
			(effects
				(font
					(size 0.7 0.7)
					(thickness 0.15)
				)
				(justify right top)
			)
		)
		(property "Datasheet" "https://industrial.panasonic.com/cdbs/www-data/pdf/RDA0000/AOA0000C301.pdf"
			(at 0 0 0)
			(layer "F.Fab")
			(hide yes)
			(effects
				(font
					(size 1.27 1.27)
					(thickness 0.15)
				)
			)
		)
		(property "Description" "SMD Chip Resistor, Jumper, 0 ohm, 100 mW, 0402 [1005 Metric], Thick Film, General Purpose"
			(at 0 0 0)
			(layer "F.Fab")
			(hide yes)
			(effects
				(font
					(size 1.27 1.27)
					(thickness 0.15)
				)
			)
		)
		(property "MPN" "ERJ2GE0R00X"
			(at 0 0 180)
			(unlocked yes)
			(layer "F.Fab")
			(hide yes)
			(effects
				(font
					(size 1 1)
					(thickness 0.15)
				)
			)
		)
		(property "Manufacturer" "Panasonic"
			(at 0 0 180)
			(unlocked yes)
			(layer "F.Fab")
			(hide yes)
			(effects
				(font
					(size 1 1)
					(thickness 0.15)
				)
			)
		)
		(property "License" "Apache-2.0"
			(at 0 0 180)
			(unlocked yes)
			(layer "F.Fab")
			(hide yes)
			(effects
				(font
					(size 1 1)
					(thickness 0.15)
				)
			)
		)
		(property "Author" "Antmicro"
			(at 0 0 180)
			(unlocked yes)
			(layer "F.Fab")
			(hide yes)
			(effects
				(font
					(size 1 1)
					(thickness 0.15)
				)
			)
		)
		(property "Val" "0R"
			(at 0 0 180)
			(unlocked yes)
			(layer "F.Fab")
			(hide yes)
			(effects
				(font
					(size 1 1)
					(thickness 0.15)
				)
			)
		)
		(property "Tolerance" "~"
			(at 0 0 180)
			(unlocked yes)
			(layer "F.Fab")
			(hide yes)
			(effects
				(font
					(size 1 1)
					(thickness 0.15)
				)
			)
		)
		(property "Current" "1A"
			(at 0 0 180)
			(unlocked yes)
			(layer "F.Fab")
			(hide yes)
			(effects
				(font
					(size 1 1)
					(thickness 0.15)
				)
			)
		)
		(sheetname "/X710-AT2 PCIe/")
		(sheetfile "x710-at2-pcie.kicad_sch")
		(attr smd)
		(fp_rect
			(start -0.925 -0.47)
			(end 0.925 0.47)
			(stroke
				(width 0.05)
				(type default)
			)
			(fill no)
			(layer "F.CrtYd")
		)
		(fp_rect
			(start -0.5 -0.25)
			(end 0.5 0.25)
			(stroke
				(width 0.15)
				(type solid)
			)
			(fill no)
			(layer "F.Fab")
		)
		(pad "1" smd roundrect
			(at -0.48 0 180)
			(size 0.59 0.64)
			(layers "F.Cu" "F.Mask" "F.Paste")
			(roundrect_rratio 0.25)
			(net 42 "/OCuLink/REFCLK.+")
			(pintype "passive")
		)
		(pad "2" smd roundrect
			(at 0.48 0 180)
			(size 0.59 0.64)
			(layers "F.Cu" "F.Mask" "F.Paste")
			(roundrect_rratio 0.25)
			(net 402 "/X710-AT2 PCIe/CLK+")
			(pintype "passive")
		)
	)
	(footprint "antmicro-footprints:R_0402_1005Metric"
		(layer "F.Cu")
		(at 58.099999 92.849999 90)
		(descr "Resistor SMD 0402")
		(tags "resistor SMD 0402")
		(property "Reference" "R31"
			(at -1.240001 1.220001 90)
			(layer "F.SilkS")
			(effects
				(font
					(size 0.7 0.7)
					(thickness 0.15)
				)
				(justify left bottom)
			)
		)
		(property "Value" "R_100k_0402"
			(at -1.011843 1.772046 90)
			(layer "F.Fab")
			(hide yes)
			(effects
				(font
					(size 0.7 0.7)
					(thickness 0.15)
				)
				(justify left bottom)
			)
		)
		(property "Datasheet" "https://www.bourns.com/docs/product-datasheets/cr.pdf"
			(at 0 0 90)
			(layer "F.Fab")
			(hide yes)
			(effects
				(font
					(size 1.27 1.27)
					(thickness 0.15)
				)
			)
		)
		(property "Description" "SMD Chip Resistor, 100 kohm, ± 1%, 62.5 mW, 0402 [1005 Metric], Thick Film, General Purpose"
			(at 0 0 90)
			(layer "F.Fab")
			(hide yes)
			(effects
				(font
					(size 1.27 1.27)
					(thickness 0.15)
				)
			)
		)
		(property "MPN" "CR0402-FX-1003GLF"
			(at 0 0 90)
			(unlocked yes)
			(layer "F.Fab")
			(hide yes)
			(effects
				(font
					(size 1 1)
					(thickness 0.15)
				)
			)
		)
		(property "Manufacturer" "Bourns"
			(at 0 0 90)
			(unlocked yes)
			(layer "F.Fab")
			(hide yes)
			(effects
				(font
					(size 1 1)
					(thickness 0.15)
				)
			)
		)
		(property "License" "Apache-2.0"
			(at 0 0 90)
			(unlocked yes)
			(layer "F.Fab")
			(hide yes)
			(effects
				(font
					(size 1 1)
					(thickness 0.15)
				)
			)
		)
		(property "Author" "Antmicro"
			(at 0 0 90)
			(unlocked yes)
			(layer "F.Fab")
			(hide yes)
			(effects
				(font
					(size 1 1)
					(thickness 0.15)
				)
			)
		)
		(property "Val" "100k"
			(at 0 0 90)
			(unlocked yes)
			(layer "F.Fab")
			(hide yes)
			(effects
				(font
					(size 1 1)
					(thickness 0.15)
				)
			)
		)
		(property "Tolerance" "1%"
			(at 0 0 90)
			(unlocked yes)
			(layer "F.Fab")
			(hide yes)
			(effects
				(font
					(size 1 1)
					(thickness 0.15)
				)
			)
		)
		(sheetname "/Power/")
		(sheetfile "power.kicad_sch")
		(attr smd)
		(fp_rect
			(start -0.925 -0.47)
			(end 0.925 0.47)
			(stroke
				(width 0.05)
				(type default)
			)
			(fill no)
			(layer "F.CrtYd")
		)
		(fp_rect
			(start -0.5 -0.25)
			(end 0.5 0.25)
			(stroke
				(width 0.15)
				(type solid)
			)
			(fill no)
			(layer "F.Fab")
		)
		(pad "1" smd roundrect
			(at -0.48 0 90)
			(size 0.59 0.64)
			(layers "F.Cu" "F.Mask" "F.Paste")
			(roundrect_rratio 0.25)
			(net 378 "/Power/DVDD_PG")
			(pintype "passive")
		)
		(pad "2" smd roundrect
			(at 0.48 0 90)
			(size 0.59 0.64)
			(layers "F.Cu" "F.Mask" "F.Paste")
			(roundrect_rratio 0.25)
			(net 326 "/Power/DVDD_VCC")
			(pintype "passive")
		)
	)
)
